# S9S_MB_2U (Grand Teton) — schematic netlist excerpt (pin names and nets, part order shuffled) for the footprints in the layout excerpt that follows; sources: Cadence DE-HDL packaged netlist, KiCad conversion of 03242023_DA0F0TMBIJ0_F0T_Motherboard_J_brd_V01_OCP.brd

R902  Q_RES  33.2 1% CHIP  pkg 0402LF  page 114 : A = PWRGD_CHE_CPU1_DIMM2 ; B = PWRGD_FAIL_CPU1_EF
C2295  Q_CAP  0.1UF 25V 10% EMPTY  pkg 0402  page 245 : A = HPDB_HSC_PWRGD_R ; B = GND

(kicad_pcb
	(version 20260206)
	(generator "pcbnew")
	(generator_version "10.0")
	(general
		(thickness 1.6)
		(legacy_teardrops no)
	)
	(paper "A4")
	(title_block
		(title "03242023_DA0F0TMBIJ0_F0T_Motherboard_J_brd_V01_OCP.brd")
		(comment 1 "Grand Teton / footprints 5703-5704 of 6105")
	)
	(layers
		(0 "F.Cu" signal "TOP")
		(4 "In1.Cu" signal "GND")
		(6 "In2.Cu" signal "IN1")
		(8 "In3.Cu" signal "GND1")
		(10 "In4.Cu" signal "IN2")
		(12 "In5.Cu" signal "GND2")
		(14 "In6.Cu" signal "IN3")
		(16 "In7.Cu" signal "GND3")
		(18 "In8.Cu" signal "VCC")
		(20 "In9.Cu" signal "VCC1")
		(22 "In10.Cu" signal "GND4")
		(24 "In11.Cu" signal "IN4")
		(26 "In12.Cu" signal "GND5")
		(28 "In13.Cu" signal "IN5")
		(30 "In14.Cu" signal "GND6")
		(32 "In15.Cu" signal "IN6")
		(34 "In16.Cu" signal "GND7")
		(2 "B.Cu" signal "BOTTOM")
		(9 "F.Adhes" user "F.Adhesive")
		(11 "B.Adhes" user "B.Adhesive")
		(13 "F.Paste" user "Package Geometry/Pastemask Top")
		(15 "B.Paste" user "Package Geometry/Pastemask Bottom")
		(5 "F.SilkS" user "Ref Des/Silkscreen Top")
		(7 "B.SilkS" user "Ref Des/Silkscreen Bottom")
		(1 "F.Mask" user "Board Geometry/Soldermask Top")
		(3 "B.Mask" user "Board Geometry/Soldermask Bottom")
		(17 "Dwgs.User" user "User.Drawings")
		(19 "Cmts.User" user "User.Comments")
		(21 "Eco1.User" user "User.Eco1")
		(23 "Eco2.User" user "User.Eco2")
		(25 "Edge.Cuts" user "Board Geometry/Outline")
		(27 "Margin" user)
		(31 "F.CrtYd" user "Package Geometry/Place Bound Top")
		(29 "B.CrtYd" user "Package Geometry/Place Bound Bottom")
		(35 "F.Fab" user "Ref Des/Assembly Top")
		(33 "B.Fab" user "Ref Des/Assembly Bottom")
	)
	(footprint ""
		(layer "B.Cu")
		(at 235.23448 -423.001948 90)
		(property "Reference" "C2295"
			(at 0 0 90)
			(layer "B.SilkS")
			(hide yes)
			(effects
				(font
					(size 1.27 1.27)
				)
				(justify mirror)
			)
		)
		(property "Value" ""
			(at 0 0 90)
			(layer "B.Fab")
			(effects
				(font
					(size 1.27 1.27)
				)
				(justify mirror)
			)
		)
		(duplicate_pad_numbers_are_jumpers no)
		(fp_line
			(start 0.7874 -0.4064)
			(end -0.7874 -0.4064)
			(stroke
				(width 0.1524)
				(type default)
			)
			(layer "B.SilkS")
		)
		(fp_line
			(start -0.7874 -0.4064)
			(end -0.7874 0.4064)
			(stroke
				(width 0.1524)
				(type default)
			)
			(layer "B.SilkS")
		)
		(fp_line
			(start 0.7874 0.4064)
			(end 0.7874 -0.4064)
			(stroke
				(width 0.1524)
				(type default)
			)
			(layer "B.SilkS")
		)
		(fp_line
			(start -0.7874 0.4064)
			(end 0.7874 0.4064)
			(stroke
				(width 0.1524)
				(type default)
			)
			(layer "B.SilkS")
		)
		(fp_line
			(start 0.67945 -0.305054)
			(end 0.12065 -0.305054)
			(stroke
				(width 0.1)
				(type default)
			)
			(layer "B.Fab")
		)
		(fp_line
			(start 0.12065 -0.305054)
			(end 0.12065 -0.2794)
			(stroke
				(width 0.1)
				(type default)
			)
			(layer "B.Fab")
		)
		(fp_line
			(start -0.12065 -0.3048)
			(end -0.67945 -0.3048)
			(stroke
				(width 0.1)
				(type default)
			)
			(layer "B.Fab")
		)
		(fp_line
			(start -0.67945 -0.3048)
			(end -0.67945 0.3048)
			(stroke
				(width 0.1)
				(type default)
			)
			(layer "B.Fab")
		)
		(fp_line
			(start 0.12065 -0.2794)
			(end -0.12065 -0.2794)
			(stroke
				(width 0.1)
				(type default)
			)
			(layer "B.Fab")
		)
		(fp_line
			(start -0.12065 -0.2794)
			(end -0.12065 -0.3048)
			(stroke
				(width 0.1)
				(type default)
			)
			(layer "B.Fab")
		)
		(fp_line
			(start 0.12065 0.2794)
			(end 0.12065 0.3048)
			(stroke
				(width 0.1)
				(type default)
			)
			(layer "B.Fab")
		)
		(fp_line
			(start -0.120396 0.2794)
			(end 0.12065 0.2794)
			(stroke
				(width 0.1)
				(type default)
			)
			(layer "B.Fab")
		)
		(fp_line
			(start 0.67945 0.3048)
			(end 0.67945 -0.305054)
			(stroke
				(width 0.1)
				(type default)
			)
			(layer "B.Fab")
		)
		(fp_line
			(start 0.12065 0.3048)
			(end 0.67945 0.3048)
			(stroke
				(width 0.1)
				(type default)
			)
			(layer "B.Fab")
		)
		(fp_line
			(start -0.120396 0.3048)
			(end -0.120396 0.2794)
			(stroke
				(width 0.1)
				(type default)
			)
			(layer "B.Fab")
		)
		(fp_line
			(start -0.67945 0.3048)
			(end -0.120396 0.3048)
			(stroke
				(width 0.1)
				(type default)
			)
			(layer "B.Fab")
		)
		(pad "1" smd circle
			(at 0.40005 0 270)
			(size 0 0)
			(layers "B.Cu" "B.Mask" "B.Paste")
			(net "HPDB_HSC_PWRGD_R")
		)
		(pad "2" smd circle
			(at -0.40005 0 270)
			(size 0 0)
			(layers "B.Cu" "B.Mask" "B.Paste")
			(net "GND")
		)
	)
	(footprint ""
		(layer "B.Cu")
		(at 163.66109 -318.717422 90)
		(property "Reference" "R902"
			(at 0 0 90)
			(layer "B.SilkS")
			(hide yes)
			(effects
				(font
					(size 1.27 1.27)
				)
				(justify mirror)
			)
		)
		(property "Value" ""
			(at 0 0 90)
			(layer "B.Fab")
			(effects
				(font
					(size 1.27 1.27)
				)
				(justify mirror)
			)
		)
		(duplicate_pad_numbers_are_jumpers no)
		(fp_line
			(start 0.7874 -0.4064)
			(end -0.7874 -0.4064)
			(stroke
				(width 0.1524)
				(type default)
			)
			(layer "B.SilkS")
		)
		(fp_line
			(start -0.7874 -0.4064)
			(end -0.7874 0.4064)
			(stroke
				(width 0.1524)
				(type default)
			)
			(layer "B.SilkS")
		)
		(fp_line
			(start 0.7874 0.4064)
			(end 0.7874 -0.4064)
			(stroke
				(width 0.1524)
				(type default)
			)
			(layer "B.SilkS")
		)
		(fp_line
			(start -0.7874 0.4064)
			(end 0.7874 0.4064)
			(stroke
				(width 0.1524)
				(type default)
			)
			(layer "B.SilkS")
		)
		(fp_line
			(start 0.67945 -0.305054)
			(end 0.12065 -0.305054)
			(stroke
				(width 0.1)
				(type default)
			)
			(layer "B.Fab")
		)
		(fp_line
			(start 0.12065 -0.305054)
			(end 0.12065 -0.2794)
			(stroke
				(width 0.1)
				(type default)
			)
			(layer "B.Fab")
		)
		(fp_line
			(start -0.12065 -0.3048)
			(end -0.67945 -0.3048)
			(stroke
				(width 0.1)
				(type default)
			)
			(layer "B.Fab")
		)
		(fp_line
			(start -0.67945 -0.3048)
			(end -0.67945 0.3048)
			(stroke
				(width 0.1)
				(type default)
			)
			(layer "B.Fab")
		)
		(fp_line
			(start 0.12065 -0.2794)
			(end -0.12065 -0.2794)
			(stroke
				(width 0.1)
				(type default)
			)
			(layer "B.Fab")
		)
		(fp_line
			(start -0.12065 -0.2794)
			(end -0.12065 -0.3048)
			(stroke
				(width 0.1)
				(type default)
			)
			(layer "B.Fab")
		)
		(fp_line
			(start 0.12065 0.2794)
			(end 0.12065 0.3048)
			(stroke
				(width 0.1)
				(type default)
			)
			(layer "B.Fab")
		)
		(fp_line
			(start -0.120396 0.2794)
			(end 0.12065 0.2794)
			(stroke
				(width 0.1)
				(type default)
			)
			(layer "B.Fab")
		)
		(fp_line
			(start 0.67945 0.3048)
			(end 0.67945 -0.305054)
			(stroke
				(width 0.1)
				(type default)
			)
			(layer "B.Fab")
		)
		(fp_line
			(start 0.12065 0.3048)
			(end 0.67945 0.3048)
			(stroke
				(width 0.1)
				(type default)
			)
			(layer "B.Fab")
		)
		(fp_line
			(start -0.120396 0.3048)
			(end -0.120396 0.2794)
			(stroke
				(width 0.1)
				(type default)
			)
			(layer "B.Fab")
		)
		(fp_line
			(start -0.67945 0.3048)
			(end -0.120396 0.3048)
			(stroke
				(width 0.1)
				(type default)
			)
			(layer "B.Fab")
		)
		(pad "1" smd circle
			(at 0.40005 0 270)
			(size 0 0)
			(layers "B.Cu" "B.Mask" "B.Paste")
			(net "PWRGD_CHE_CPU1_DIMM2")
		)
		(pad "2" smd circle
			(at -0.40005 0 270)
			(size 0 0)
			(layers "B.Cu" "B.Mask" "B.Paste")
			(net "PWRGD_FAIL_CPU1_EF")
		)
	)
)
